(kicad_pcb
	(version 20260206)
	(generator "pcbnew")
	(generator_version "10.0")
	(general
		(thickness 1.6)
		(legacy_teardrops no)
	)
	(paper "A4")
	(title_block
		(title "panther-plus-userver — 13130-1b_20150205.brd")
		(comment 1 "Honey Badger (Wiwynn) / footprints 1151-1159 of 1509")
	)
	(layers
		(0 "F.Cu" signal "TOP")
		(4 "In1.Cu" signal "L2")
		(6 "In2.Cu" signal "L3")
		(8 "In3.Cu" signal "L4")
		(10 "In4.Cu" signal "L5")
		(12 "In5.Cu" signal "L6")
		(14 "In6.Cu" signal "L7")
		(16 "In7.Cu" signal "L8")
		(18 "In8.Cu" signal "L9")
		(20 "In9.Cu" signal "L10")
		(22 "In10.Cu" signal "L11")
		(2 "B.Cu" signal "BOTTOM")
		(9 "F.Adhes" user "F.Adhesive")
		(11 "B.Adhes" user "B.Adhesive")
		(13 "F.Paste" user "Package Geometry/Pastemask Top")
		(15 "B.Paste" user "Package Geometry/Pastemask Bottom")
		(5 "F.SilkS" user "Ref Des/Silkscreen Top")
		(7 "B.SilkS" user "Ref Des/Silkscreen Bottom")
		(1 "F.Mask" user "Board Geometry/Soldermask Top")
		(3 "B.Mask" user "Board Geometry/Soldermask Bottom")
		(17 "Dwgs.User" user "User.Drawings")
		(19 "Cmts.User" user "User.Comments")
		(21 "Eco1.User" user "User.Eco1")
		(23 "Eco2.User" user "User.Eco2")
		(25 "Edge.Cuts" user "Board Geometry/Outline")
		(27 "Margin" user)
		(31 "F.CrtYd" user "Package Geometry/Place Bound Top")
		(29 "B.CrtYd" user "Package Geometry/Place Bound Bottom")
		(35 "F.Fab" user "Ref Des/Assembly Top")
		(33 "B.Fab" user "Ref Des/Assembly Bottom")
	)
	(footprint ""
		(layer "B.Cu")
		(at 77.343 -21.209 180)
		(property "Reference" "PR222"
			(at 0 0 0)
			(layer "B.SilkS")
			(hide yes)
			(effects
				(font
					(size 1.27 1.27)
				)
				(justify mirror)
			)
		)
		(property "Value" "10KR2F-2-GP"
			(at -0.064008 -3.993896 180)
			(unlocked yes)
			(layer "B.Fab")
			(hide yes)
			(effects
				(font
					(size 1.016 1.016)
					(thickness 0.1524)
				)
				(justify mirror)
			)
		)
		(property "Device Type" "R402H16"
			(at -0.064008 -5.517896 180)
			(unlocked yes)
			(layer "B.Fab")
			(hide yes)
			(effects
				(font
					(size 1.016 1.016)
					(thickness 0.1524)
				)
				(justify mirror)
			)
		)
		(duplicate_pad_numbers_are_jumpers no)
		(fp_rect
			(start 0.381 0.8382)
			(end -0.381 -0.8382)
			(stroke
				(width 0)
				(type default)
			)
			(fill no)
			(layer "B.CrtYd")
		)
		(fp_rect
			(start 0.381 0.8382)
			(end -0.381 -0.8382)
			(stroke
				(width 0)
				(type default)
			)
			(fill no)
			(layer "B.Fab")
		)
		(pad "1" smd custom
			(at 0 -0.4318)
			(size 0.127 0.127)
			(layers "B.Cu" "B.Mask" "B.Paste")
			(net "PWRGD_P1V35_PG")
			(options
				(clearance outline)
				(anchor circle)
			)
			(primitives
				(gr_poly
					(pts
						(arc
							(start -0.2032 0.2794)
							(mid -0.239121 0.264521)
							(end -0.254 0.2286)
						)
						(arc
							(start -0.254 -0.2286)
							(mid -0.239121 -0.264521)
							(end -0.2032 -0.2794)
						)
						(arc
							(start 0.2032 -0.2794)
							(mid 0.239121 -0.264521)
							(end 0.254 -0.2286)
						)
						(arc
							(start 0.254 0.2286)
							(mid 0.239121 0.264521)
							(end 0.2032 0.2794)
						)
					)
					(width 0)
					(fill yes)
				)
			)
		)
		(pad "2" smd custom
			(at 0 0.4318)
			(size 0.127 0.127)
			(layers "B.Cu" "B.Mask" "B.Paste")
			(net "P3V3_STBY")
			(options
				(clearance outline)
				(anchor circle)
			)
			(primitives
				(gr_poly
					(pts
						(arc
							(start -0.2032 0.2794)
							(mid -0.239121 0.264521)
							(end -0.254 0.2286)
						)
						(arc
							(start -0.254 -0.2286)
							(mid -0.239121 -0.264521)
							(end -0.2032 -0.2794)
						)
						(arc
							(start 0.2032 -0.2794)
							(mid 0.239121 -0.264521)
							(end 0.254 -0.2286)
						)
						(arc
							(start 0.254 0.2286)
							(mid 0.239121 0.264521)
							(end 0.2032 0.2794)
						)
					)
					(width 0)
					(fill yes)
				)
			)
		)
	)
	(footprint ""
		(layer "B.Cu")
		(at 34.163 -51.054 -90)
		(property "Reference" "PC131"
			(at 0 0 90)
			(layer "B.SilkS")
			(hide yes)
			(effects
				(font
					(size 1.27 1.27)
				)
				(justify mirror)
			)
		)
		(property "Value" "SCD1U16V2KX-3GP"
			(at -1.8923 -1.2065 270)
			(unlocked yes)
			(layer "B.Fab")
			(hide yes)
			(effects
				(font
					(size 1.016 1.016)
					(thickness 0.1524)
				)
				(justify mirror)
			)
		)
		(property "Device Type" "C402H22"
			(at -1.8923 -2.7305 270)
			(unlocked yes)
			(layer "B.Fab")
			(hide yes)
			(effects
				(font
					(size 1.016 1.016)
					(thickness 0.1524)
				)
				(justify mirror)
			)
		)
		(duplicate_pad_numbers_are_jumpers no)
		(fp_rect
			(start 0.381 0.7366)
			(end -0.381 -0.7366)
			(stroke
				(width 0)
				(type default)
			)
			(fill no)
			(layer "B.CrtYd")
		)
		(fp_rect
			(start 0.381 0.7366)
			(end -0.381 -0.7366)
			(stroke
				(width 0)
				(type default)
			)
			(fill no)
			(layer "B.Fab")
		)
		(pad "1" smd custom
			(at 0 -0.4572 90)
			(size 0.1143 0.1143)
			(layers "B.Cu" "B.Mask" "B.Paste")
			(net "P1V5_STBY_EN")
			(options
				(clearance outline)
				(anchor circle)
			)
			(primitives
				(gr_poly
					(pts
						(arc
							(start -0.254 0.1778)
							(mid -0.239121 0.213721)
							(end -0.2032 0.2286)
						)
						(arc
							(start 0.2032 0.2286)
							(mid 0.239121 0.213721)
							(end 0.254 0.1778)
						)
						(arc
							(start 0.254 -0.1778)
							(mid 0.239121 -0.213721)
							(end 0.2032 -0.2286)
						)
						(arc
							(start -0.2032 -0.2286)
							(mid -0.239121 -0.213721)
							(end -0.254 -0.1778)
						)
					)
					(width 0)
					(fill yes)
				)
			)
		)
		(pad "2" smd custom
			(at 0 0.4572 90)
			(size 0.1143 0.1143)
			(layers "B.Cu" "B.Mask" "B.Paste")
			(net "GND")
			(options
				(clearance outline)
				(anchor circle)
			)
			(primitives
				(gr_poly
					(pts
						(arc
							(start -0.254 0.1778)
							(mid -0.239121 0.213721)
							(end -0.2032 0.2286)
						)
						(arc
							(start 0.2032 0.2286)
							(mid 0.239121 0.213721)
							(end 0.254 0.1778)
						)
						(arc
							(start 0.254 -0.1778)
							(mid 0.239121 -0.213721)
							(end 0.2032 -0.2286)
						)
						(arc
							(start -0.2032 -0.2286)
							(mid -0.239121 -0.213721)
							(end -0.254 -0.1778)
						)
					)
					(width 0)
					(fill yes)
				)
			)
		)
	)
	(footprint ""
		(layer "B.Cu")
		(at 99.568 -19.431)
		(property "Reference" "C257"
			(at 0 0 0)
			(layer "B.SilkS")
			(hide yes)
			(effects
				(font
					(size 1.27 1.27)
				)
				(justify mirror)
			)
		)
		(property "Value" "SCD1U16V2JX-1-GP"
			(at -1.1811 -2.7051 0)
			(unlocked yes)
			(layer "B.Fab")
			(hide yes)
			(effects
				(font
					(size 1.016 1.016)
					(thickness 0.1524)
				)
				(justify mirror)
			)
		)
		(property "Device Type" "C402H22"
			(at -1.1811 -4.2291 0)
			(unlocked yes)
			(layer "B.Fab")
			(hide yes)
			(effects
				(font
					(size 1.016 1.016)
					(thickness 0.1524)
				)
				(justify mirror)
			)
		)
		(duplicate_pad_numbers_are_jumpers no)
		(fp_rect
			(start 0.381 0.7366)
			(end -0.381 -0.7366)
			(stroke
				(width 0)
				(type default)
			)
			(fill no)
			(layer "B.CrtYd")
		)
		(fp_rect
			(start 0.381 0.7366)
			(end -0.381 -0.7366)
			(stroke
				(width 0)
				(type default)
			)
			(fill no)
			(layer "B.Fab")
		)
		(pad "1" smd custom
			(at 0 -0.4572 180)
			(size 0.1143 0.1143)
			(layers "B.Cu" "B.Mask" "B.Paste")
			(net "VCCCLKDDR1")
			(options
				(clearance outline)
				(anchor circle)
			)
			(primitives
				(gr_poly
					(pts
						(arc
							(start -0.254 0.1778)
							(mid -0.239121 0.213721)
							(end -0.2032 0.2286)
						)
						(arc
							(start 0.2032 0.2286)
							(mid 0.239121 0.213721)
							(end 0.254 0.1778)
						)
						(arc
							(start 0.254 -0.1778)
							(mid 0.239121 -0.213721)
							(end 0.2032 -0.2286)
						)
						(arc
							(start -0.2032 -0.2286)
							(mid -0.239121 -0.213721)
							(end -0.254 -0.1778)
						)
					)
					(width 0)
					(fill yes)
				)
			)
		)
		(pad "2" smd custom
			(at 0 0.4572 180)
			(size 0.1143 0.1143)
			(layers "B.Cu" "B.Mask" "B.Paste")
			(net "GND")
			(options
				(clearance outline)
				(anchor circle)
			)
			(primitives
				(gr_poly
					(pts
						(arc
							(start -0.254 0.1778)
							(mid -0.239121 0.213721)
							(end -0.2032 0.2286)
						)
						(arc
							(start 0.2032 0.2286)
							(mid 0.239121 0.213721)
							(end 0.254 0.1778)
						)
						(arc
							(start 0.254 -0.1778)
							(mid 0.239121 -0.213721)
							(end 0.2032 -0.2286)
						)
						(arc
							(start -0.2032 -0.2286)
							(mid -0.239121 -0.213721)
							(end -0.254 -0.1778)
						)
					)
					(width 0)
					(fill yes)
				)
			)
		)
	)
	(footprint ""
		(layer "B.Cu")
		(at 15.875 -24.003 90)
		(property "Reference" "PR96"
			(at 0 0 90)
			(layer "B.SilkS")
			(hide yes)
			(effects
				(font
					(size 1.27 1.27)
				)
				(justify mirror)
			)
		)
		(property "Value" "15KR2F-GP"
			(at -1.7907 -1.1176 90)
			(unlocked yes)
			(layer "B.Fab")
			(hide yes)
			(effects
				(font
					(size 1.016 1.016)
					(thickness 0.1524)
				)
				(justify mirror)
			)
		)
		(property "Device Type" "R402H16"
			(at -1.7907 -2.6416 90)
			(unlocked yes)
			(layer "B.Fab")
			(hide yes)
			(effects
				(font
					(size 1.016 1.016)
					(thickness 0.1524)
				)
				(justify mirror)
			)
		)
		(duplicate_pad_numbers_are_jumpers no)
		(fp_rect
			(start 0.381 0.8382)
			(end -0.381 -0.8382)
			(stroke
				(width 0)
				(type default)
			)
			(fill no)
			(layer "B.CrtYd")
		)
		(fp_rect
			(start 0.381 0.8382)
			(end -0.381 -0.8382)
			(stroke
				(width 0)
				(type default)
			)
			(fill no)
			(layer "B.Fab")
		)
		(pad "1" smd custom
			(at 0 -0.4318 270)
			(size 0.127 0.127)
			(layers "B.Cu" "B.Mask" "B.Paste")
			(net "GND")
			(options
				(clearance outline)
				(anchor circle)
			)
			(primitives
				(gr_poly
					(pts
						(arc
							(start -0.2032 0.2794)
							(mid -0.239121 0.264521)
							(end -0.254 0.2286)
						)
						(arc
							(start -0.254 -0.2286)
							(mid -0.239121 -0.264521)
							(end -0.2032 -0.2794)
						)
						(arc
							(start 0.2032 -0.2794)
							(mid 0.239121 -0.264521)
							(end 0.254 -0.2286)
						)
						(arc
							(start 0.254 0.2286)
							(mid 0.239121 0.264521)
							(end 0.2032 0.2794)
						)
					)
					(width 0)
					(fill yes)
				)
			)
		)
		(pad "2" smd custom
			(at 0 0.4318 270)
			(size 0.127 0.127)
			(layers "B.Cu" "B.Mask" "B.Paste")
			(net "PG_P1V0")
			(options
				(clearance outline)
				(anchor circle)
			)
			(primitives
				(gr_poly
					(pts
						(arc
							(start -0.2032 0.2794)
							(mid -0.239121 0.264521)
							(end -0.254 0.2286)
						)
						(arc
							(start -0.254 -0.2286)
							(mid -0.239121 -0.264521)
							(end -0.2032 -0.2794)
						)
						(arc
							(start 0.2032 -0.2794)
							(mid 0.239121 -0.264521)
							(end 0.254 -0.2286)
						)
						(arc
							(start 0.254 0.2286)
							(mid 0.239121 0.264521)
							(end 0.2032 0.2794)
						)
					)
					(width 0)
					(fill yes)
				)
			)
		)
	)
	(footprint ""
		(layer "B.Cu")
		(at 88.011 -18.542)
		(property "Reference" "PR221"
			(at 0 0 0)
			(layer "B.SilkS")
			(hide yes)
			(effects
				(font
					(size 1.27 1.27)
				)
				(justify mirror)
			)
		)
		(property "Value" "0R6J-3-GP"
			(at 0.0508 -4.8514 0)
			(unlocked yes)
			(layer "B.Fab")
			(hide yes)
			(effects
				(font
					(size 1.016 1.016)
					(thickness 0.1524)
				)
				(justify mirror)
			)
		)
		(property "Device Type" "R1206H28"
			(at 0 -6.3754 0)
			(unlocked yes)
			(layer "B.Fab")
			(hide yes)
			(effects
				(font
					(size 1.016 1.016)
					(thickness 0.1524)
				)
				(justify mirror)
			)
		)
		(duplicate_pad_numbers_are_jumpers no)
		(fp_line
			(start -0.7239 -0.381)
			(end 0.7239 -0.381)
			(stroke
				(width 0.1524)
				(type default)
			)
			(layer "B.SilkS")
		)
		(fp_line
			(start -0.7239 0.381)
			(end -0.7239 -0.381)
			(stroke
				(width 0.1524)
				(type default)
			)
			(layer "B.SilkS")
		)
		(fp_line
			(start 0.7239 -0.381)
			(end 0.7239 0.381)
			(stroke
				(width 0.1524)
				(type default)
			)
			(layer "B.SilkS")
		)
		(fp_line
			(start 0.7239 0.381)
			(end -0.7239 0.381)
			(stroke
				(width 0.1524)
				(type default)
			)
			(layer "B.SilkS")
		)
		(fp_poly
			(pts
				(xy 0.7239 0.381) (xy -0.7239 0.381) (xy -0.7239 -0.381) (xy 0.7239 -0.381)
			)
			(stroke
				(width 0)
				(type default)
			)
			(fill yes)
			(layer "B.SilkS")
		)
		(fp_rect
			(start 1.0541 1.9812)
			(end -1.0541 -1.9812)
			(stroke
				(width 0)
				(type default)
			)
			(fill no)
			(layer "B.CrtYd")
		)
		(fp_rect
			(start 1.0541 1.9812)
			(end -1.0541 -1.9812)
			(stroke
				(width 0)
				(type default)
			)
			(fill no)
			(layer "B.Fab")
		)
		(pad "1" smd rect
			(at 0 -1.3462 180)
			(size 1.8542 1.016)
			(layers "B.Cu" "B.Mask" "B.Paste")
			(net "P1V35")
		)
		(pad "2" smd rect
			(at 0 1.3462 180)
			(size 1.8542 1.016)
			(layers "B.Cu" "B.Mask" "B.Paste")
			(net "TPS74801_1V35_OUT")
		)
	)
	(footprint ""
		(layer "B.Cu")
		(at 75.819 -61.849)
		(property "Reference" "R190"
			(at 0 0 0)
			(layer "B.SilkS")
			(hide yes)
			(effects
				(font
					(size 1.27 1.27)
				)
				(justify mirror)
			)
		)
		(property "Value" "0R2J-2-GP"
			(at -0.064008 -3.993896 0)
			(unlocked yes)
			(layer "B.Fab")
			(hide yes)
			(effects
				(font
					(size 1.016 1.016)
					(thickness 0.1524)
				)
				(justify mirror)
			)
		)
		(property "Device Type" "R402H16"
			(at -0.064008 -5.517896 0)
			(unlocked yes)
			(layer "B.Fab")
			(hide yes)
			(effects
				(font
					(size 1.016 1.016)
					(thickness 0.1524)
				)
				(justify mirror)
			)
		)
		(duplicate_pad_numbers_are_jumpers no)
		(fp_rect
			(start 0.381 0.8382)
			(end -0.381 -0.8382)
			(stroke
				(width 0)
				(type default)
			)
			(fill no)
			(layer "B.CrtYd")
		)
		(fp_rect
			(start 0.381 0.8382)
			(end -0.381 -0.8382)
			(stroke
				(width 0)
				(type default)
			)
			(fill no)
			(layer "B.Fab")
		)
		(pad "1" smd custom
			(at 0 -0.4318 180)
			(size 0.127 0.127)
			(layers "B.Cu" "B.Mask" "B.Paste")
			(net "PVNN")
			(options
				(clearance outline)
				(anchor circle)
			)
			(primitives
				(gr_poly
					(pts
						(arc
							(start -0.2032 0.2794)
							(mid -0.239121 0.264521)
							(end -0.254 0.2286)
						)
						(arc
							(start -0.254 -0.2286)
							(mid -0.239121 -0.264521)
							(end -0.2032 -0.2794)
						)
						(arc
							(start 0.2032 -0.2794)
							(mid 0.239121 -0.264521)
							(end 0.254 -0.2286)
						)
						(arc
							(start 0.254 0.2286)
							(mid 0.239121 0.264521)
							(end 0.2032 0.2794)
						)
					)
					(width 0)
					(fill yes)
				)
			)
		)
		(pad "2" smd custom
			(at 0 0.4318 180)
			(size 0.127 0.127)
			(layers "B.Cu" "B.Mask" "B.Paste")
			(net "PVNN_SENSE")
			(options
				(clearance outline)
				(anchor circle)
			)
			(primitives
				(gr_poly
					(pts
						(arc
							(start -0.2032 0.2794)
							(mid -0.239121 0.264521)
							(end -0.254 0.2286)
						)
						(arc
							(start -0.254 -0.2286)
							(mid -0.239121 -0.264521)
							(end -0.2032 -0.2794)
						)
						(arc
							(start 0.2032 -0.2794)
							(mid 0.239121 -0.264521)
							(end 0.254 -0.2286)
						)
						(arc
							(start 0.254 0.2286)
							(mid 0.239121 0.264521)
							(end 0.2032 0.2794)
						)
					)
					(width 0)
					(fill yes)
				)
			)
		)
	)
	(footprint ""
		(layer "B.Cu")
		(at 95.2754 -30.1498 -90)
		(property "Reference" "TP48"
			(at 0 0 90)
			(layer "B.SilkS")
			(hide yes)
			(effects
				(font
					(size 1.27 1.27)
				)
				(justify mirror)
			)
		)
		(property "Value" "TPAD24"
			(at 0 -2.9972 270)
			(unlocked yes)
			(layer "B.Fab")
			(hide yes)
			(effects
				(font
					(size 1.016 1.016)
					(thickness 0.1524)
				)
				(justify mirror)
			)
		)
		(property "Device Type" "TPAD24"
			(at 0 -4.5212 270)
			(unlocked yes)
			(layer "B.Fab")
			(hide yes)
			(effects
				(font
					(size 1.016 1.016)
					(thickness 0.1524)
				)
				(justify mirror)
			)
		)
		(duplicate_pad_numbers_are_jumpers no)
		(fp_poly
			(pts
				(arc
					(start 0 -0.3048)
					(mid 0 0.3048)
					(end 0 -0.3048)
				)
			)
			(stroke
				(width 0)
				(type default)
			)
			(fill no)
			(layer "B.CrtYd")
		)
		(fp_poly
			(pts
				(arc
					(start 0 -0.6096)
					(mid 0 0.6096)
					(end 0 -0.6096)
				)
			)
			(stroke
				(width 0)
				(type default)
			)
			(fill no)
			(layer "B.Fab")
		)
		(pad "1" smd circle
			(at 0 0 90)
			(size 0.6096 0.6096)
			(layers "B.Cu" "B.Mask" "B.Paste")
			(net "TP_CPU_RSVD15")
		)
	)
	(footprint ""
		(layer "B.Cu")
		(at 66.3702 -23.3426 180)
		(property "Reference" "R394"
			(at 0 0 0)
			(layer "B.SilkS")
			(hide yes)
			(effects
				(font
					(size 1.27 1.27)
				)
				(justify mirror)
			)
		)
		(property "Value" "300R2F-GP"
			(at -1.7907 -1.1176 180)
			(unlocked yes)
			(layer "B.Fab")
			(hide yes)
			(effects
				(font
					(size 1.016 1.016)
					(thickness 0.1524)
				)
				(justify mirror)
			)
		)
		(property "Device Type" "R402H16"
			(at -1.7907 -2.6416 180)
			(unlocked yes)
			(layer "B.Fab")
			(hide yes)
			(effects
				(font
					(size 1.016 1.016)
					(thickness 0.1524)
				)
				(justify mirror)
			)
		)
		(duplicate_pad_numbers_are_jumpers no)
		(fp_rect
			(start 0.381 0.8382)
			(end -0.381 -0.8382)
			(stroke
				(width 0)
				(type default)
			)
			(fill no)
			(layer "B.CrtYd")
		)
		(fp_rect
			(start 0.381 0.8382)
			(end -0.381 -0.8382)
			(stroke
				(width 0)
				(type default)
			)
			(fill no)
			(layer "B.Fab")
		)
		(pad "1" smd custom
			(at 0 -0.4318)
			(size 0.127 0.127)
			(layers "B.Cu" "B.Mask" "B.Paste")
			(net "P3V3")
			(options
				(clearance outline)
				(anchor circle)
			)
			(primitives
				(gr_poly
					(pts
						(arc
							(start -0.2032 0.2794)
							(mid -0.239121 0.264521)
							(end -0.254 0.2286)
						)
						(arc
							(start -0.254 -0.2286)
							(mid -0.239121 -0.264521)
							(end -0.2032 -0.2794)
						)
						(arc
							(start 0.2032 -0.2794)
							(mid 0.239121 -0.264521)
							(end 0.254 -0.2286)
						)
						(arc
							(start 0.254 0.2286)
							(mid 0.239121 0.264521)
							(end 0.2032 0.2794)
						)
					)
					(width 0)
					(fill yes)
				)
			)
		)
		(pad "2" smd custom
			(at 0 0.4318)
			(size 0.127 0.127)
			(layers "B.Cu" "B.Mask" "B.Paste")
			(net "LED_MSATA_DAS_R")
			(options
				(clearance outline)
				(anchor circle)
			)
			(primitives
				(gr_poly
					(pts
						(arc
							(start -0.2032 0.2794)
							(mid -0.239121 0.264521)
							(end -0.254 0.2286)
						)
						(arc
							(start -0.254 -0.2286)
							(mid -0.239121 -0.264521)
							(end -0.2032 -0.2794)
						)
						(arc
							(start 0.2032 -0.2794)
							(mid 0.239121 -0.264521)
							(end 0.254 -0.2286)
						)
						(arc
							(start 0.254 0.2286)
							(mid 0.239121 0.264521)
							(end 0.2032 0.2794)
						)
					)
					(width 0)
					(fill yes)
				)
			)
		)
	)
	(footprint ""
		(layer "B.Cu")
		(at 203.2 -70.993 -90)
		(property "Reference" "R1"
			(at 0 0 90)
			(layer "B.SilkS")
			(hide yes)
			(effects
				(font
					(size 1.27 1.27)
				)
				(justify mirror)
			)
		)
		(property "Value" "1KR5F-1-GP"
			(at 0 -4.9022 270)
			(unlocked yes)
			(layer "B.Fab")
			(hide yes)
			(effects
				(font
					(size 1.016 1.016)
					(thickness 0.1524)
				)
				(justify mirror)
			)
		)
		(property "Device Type" "R805H24"
			(at 0 -6.8072 270)
			(unlocked yes)
			(layer "B.Fab")
			(hide yes)
			(effects
				(font
					(size 1.016 1.016)
					(thickness 0.1524)
				)
				(justify mirror)
			)
		)
		(duplicate_pad_numbers_are_jumpers no)
		(fp_line
			(start -0.6096 0)
			(end -0.2794 0)
			(stroke
				(width 0.3048)
				(type default)
			)
			(layer "B.SilkS")
		)
		(fp_line
			(start 0.2794 0)
			(end 0.6096 0)
			(stroke
				(width 0.3048)
				(type default)
			)
			(layer "B.SilkS")
		)
		(fp_poly
			(pts
				(xy 0.9017 1.4351) (xy -0.9017 1.4351) (xy -0.9017 -1.4351) (xy 0.9017 -1.4351)
			)
			(stroke
				(width 0)
				(type default)
			)
			(fill no)
			(layer "B.CrtYd")
		)
		(fp_poly
			(pts
				(xy -0.9017 1.4351) (xy -0.9017 -1.4351) (xy 0.9017 -1.4351) (xy 0.9017 1.4351)
			)
			(stroke
				(width 0)
				(type default)
			)
			(fill no)
			(layer "B.Fab")
		)
		(pad "1" smd rect
			(at 0 -0.8382 90)
			(size 1.5494 0.9398)
			(layers "B.Cu" "B.Mask" "B.Paste")
			(net "P12V")
		)
		(pad "2" smd rect
			(at 0 0.8382 90)
			(size 1.5494 0.9398)
			(layers "B.Cu" "B.Mask" "B.Paste")
			(net "PWR_STATUS_LED")
		)
	)
)
